#ISCELL
  mstr_symbols design_note *
  *
#ISCELL
  mstr_symbols intel_corp_bpage *
  *
#ISCELL
  mstr_symbols gnd *
  page194_i100
#CELL
  mstr_discrete capp *
  page194_i101
#ISCELL
  mstr_symbols vcc_core *
  page194_i102
#ISCELL
  mstr_symbols gnd *
  page194_i110
#ISCELL
  mstr_symbols gnd *
  page194_i111
#ISCELL
  mstr_standard offpage *
  page194_i114
#ISCELL
  mstr_standard offpage *
  page194_i116
#ISCELL
  mstr_symbols p12v_stby *
  page194_i119
#ISCELL
  mstr_symbols p3v3_stby *
  page194_i120
#ISCELL
  mstr_symbols p5v_stby *
  page194_i121
#ISCELL
  mstr_standard offpage *
  page194_i123
#ISCELL
  mstr_standard offpage *
  page194_i124
#ISCELL
  mstr_standard offpage *
  page194_i125
#ISCELL
  mstr_symbols gnd *
  page194_i127
#ISCELL
  mstr_symbols vcc_core *
  page194_i130
#ISCELL
  mstr_standard offpage *
  page194_i131
#ISCELL
  mstr_standard offpage *
  page194_i132
#ISCELL
  mstr_standard offpage *
  page194_i133
#ISCELL
  mstr_standard offpage *
  page194_i134
#ISCELL
  mstr_symbols vcc_core *
  page194_i141
#ISCELL
  mstr_symbols vcc_core *
  page194_i142
#ISCELL
  mstr_symbols vcc_core *
  page194_i143
#ISCELL
  mstr_symbols vcc_core *
  page194_i144
#ISCELL
  mstr_standard offpage *
  page194_i148
#CELL
  dev_discrete cap_a *
  page194_i149
#CELL
  dev_discrete cap_a *
  page194_i150
#ISCELL
  mstr_symbols gnd *
  page194_i151
#ISCELL
  mstr_symbols pvccio_cpu0 *
  page194_i154
#CELL
  mstr_discrete res *
  page194_i155
#CELL
  mstr_discrete res *
  page194_i156
#ISCELL
  mstr_symbols gnd *
  page194_i157
#ISCELL
  mstr_standard offpage *
  page194_i158
#ISCELL
  mstr_standard offpage *
  page194_i159
#CELL
  dev_discrete cap_a *
  page194_i16
#ISCELL
  mstr_standard offpage *
  page194_i160
#ISCELL
  mstr_standard offpage *
  page194_i161
#ISCELL
  mstr_standard offpage *
  page194_i162
#ISCELL
  mstr_standard offpage *
  page194_i163
#ISCELL
  mstr_standard offpage *
  page194_i164
#ISCELL
  mstr_standard offpage *
  page194_i165
#ISCELL
  mstr_standard offpage *
  page194_i166
#ISCELL
  mstr_standard offpage *
  page194_i167
#ISCELL
  mstr_symbols p3v3 *
  page194_i170
#ISCELL
  mstr_standard offpage *
  page194_i171
#ISCELL
  mstr_symbols gnd *
  page194_i28
#CELL
  mstr_discrete capp *
  page194_i29
#ISCELL
  mstr_symbols vcc_core *
  page194_i30
#CELL
  mstr_discrete capp *
  page194_i31
#ISCELL
  mstr_symbols gnd *
  page194_i33
#CELL
  mstr_sconn sconn120_h61426002 *
  page194_i55
#CELL
  mstr_sconn sconn120_h61426002 *
  page194_i56
#ISCELL
  mstr_symbols gnd *
  page194_i61
#ISCELL
  mstr_symbols gnd *
  page194_i62
#ISCELL
  mstr_standard offpage *
  page194_i64
#ISCELL
  mstr_standard offpage *
  page194_i67
#ISCELL
  mstr_symbols vcc_core *
  page194_i68
#ISCELL
  mstr_symbols vcc_core *
  page194_i69
#CELL
  dev_discrete cap_a *
  page194_i86
#CELL
  dev_discrete cap_a *
  page194_i9
#ISCELL
  mstr_symbols gnd *
  page194_i92
#ISCELL
  mstr_symbols vcc_core *
  page194_i95
#CELL
  dev_discrete cap_a *
  page194_i99
